(kicad_pcb
	(version 20260206)
	(generator "pcbnew")
	(generator_version "10.0")
	(general
		(thickness 1.21888)
		(legacy_teardrops no)
	)
	(paper "A4")
	(title_block
		(title "timecard-proto-v0 — Timingcard_PCB.PcbDoc")
		(comment 1 "Time Appliance Project (Time Card) / footprint 31 of 167 (P1), pads 131-263 of 340")
	)
	(layers
		(0 "F.Cu" signal "TOP")
		(4 "In1.Cu" signal "SGND")
		(6 "In2.Cu" signal "IN1")
		(8 "In3.Cu" signal "IN2")
		(10 "In4.Cu" signal "SGND1")
		(2 "B.Cu" signal "BOTTOM")
		(9 "F.Adhes" user "F.Adhesive")
		(11 "B.Adhes" user "B.Adhesive")
		(13 "F.Paste" user "Top Paste")
		(15 "B.Paste" user "Bottom Paste")
		(5 "F.SilkS" user "Top Overlay")
		(7 "B.SilkS" user "Bottom Overlay")
		(1 "F.Mask" user "Top Solder")
		(3 "B.Mask" user "Bottom Solder")
		(17 "Dwgs.User" user "User.Drawings")
		(19 "Cmts.User" user "User.Comments")
		(21 "Eco1.User" user "User.Eco1")
		(23 "Eco2.User" user "User.Eco2")
		(25 "Edge.Cuts" user)
		(27 "Margin" user)
		(31 "F.CrtYd" user "Top Courtyard")
		(29 "B.CrtYd" user "Bottom Courtyard")
		(35 "F.Fab" user "Top Component Center")
		(33 "B.Fab" user "Bottom Component Center")
	)
	(footprint "FPGA_CONN:FPGA_CONN"
		(locked yes)
		(layer "F.Cu")
		(at 125.389655 117.45847)
		(property "Reference" "P1"
			(at -27.35726 -23.285325 0)
			(unlocked yes)
			(layer "F.SilkS")
			(effects
				(font
					(size 0.762 0.762)
					(thickness 0.2286)
				)
				(justify left bottom)
			)
		)
		(property "Value" "FPGA_CONN"
			(at -43.9575 52.70297 0)
			(unlocked yes)
			(layer "F.SilkS")
			(hide yes)
			(effects
				(font
					(size 1.524 1.524)
					(thickness 0.254)
				)
				(justify left bottom)
			)
		)
		(sheetname "FPGA")
		(sheetfile "FPGA.kicad_sch")
		(duplicate_pad_numbers_are_jumpers no)
		(pad "B-47" smd rect
			(at 0.7987 -16.77035)
			(size 0.24994 1.54991)
			(layers "F.Cu" "F.Mask" "F.Paste")
			(net "MAC_PPS_IN0-")
		)
		(pad "B-48" smd rect
			(at 0.7987 -20.82012)
			(size 0.24994 1.54991)
			(layers "F.Cu" "F.Mask" "F.Paste")
		)
		(pad "B-49" smd rect
			(at 1.29857 -16.77035)
			(size 0.24994 1.54991)
			(layers "F.Cu" "F.Mask" "F.Paste")
			(net "GND")
		)
		(pad "B-50" smd rect
			(at 1.29857 -20.82012)
			(size 0.24994 1.54991)
			(layers "F.Cu" "F.Mask" "F.Paste")
			(net "GND")
		)
		(pad "B-51" smd rect
			(at 1.7987 -16.77035)
			(size 0.24994 1.54991)
			(layers "F.Cu" "F.Mask" "F.Paste")
			(net "MAC_PPS_IN1+")
		)
		(pad "B-52" smd rect
			(at 1.7987 -20.82012)
			(size 0.24994 1.54991)
			(layers "F.Cu" "F.Mask" "F.Paste")
		)
		(pad "B-53" smd rect
			(at 2.29857 -16.77035)
			(size 0.24994 1.54991)
			(layers "F.Cu" "F.Mask" "F.Paste")
			(net "MAC_PPS_IN1-")
		)
		(pad "B-54" smd rect
			(at 2.29857 -20.82012)
			(size 0.24994 1.54991)
			(layers "F.Cu" "F.Mask" "F.Paste")
		)
		(pad "B-55" smd rect
			(at 2.7987 -16.77035)
			(size 0.24994 1.54991)
			(layers "F.Cu" "F.Mask" "F.Paste")
		)
		(pad "B-56" smd rect
			(at 2.7987 -20.82012)
			(size 0.24994 1.54991)
			(layers "F.Cu" "F.Mask" "F.Paste")
		)
		(pad "B-57" smd rect
			(at 3.29857 -16.77035)
			(size 0.24994 1.54991)
			(layers "F.Cu" "F.Mask" "F.Paste")
		)
		(pad "B-58" smd rect
			(at 3.29857 -20.82012)
			(size 0.24994 1.54991)
			(layers "F.Cu" "F.Mask" "F.Paste")
		)
		(pad "B-59" smd rect
			(at 3.7987 -16.77035)
			(size 0.24994 1.54991)
			(layers "F.Cu" "F.Mask" "F.Paste")
			(net "GND")
		)
		(pad "B-60" smd rect
			(at 3.7987 -20.82012)
			(size 0.24994 1.54991)
			(layers "F.Cu" "F.Mask" "F.Paste")
			(net "GND")
		)
		(pad "B-61" smd rect
			(at 4.29857 -16.77035)
			(size 0.24994 1.54991)
			(layers "F.Cu" "F.Mask" "F.Paste")
			(net "SDA")
		)
		(pad "B-62" smd rect
			(at 4.29857 -20.82012)
			(size 0.24994 1.54991)
			(layers "F.Cu" "F.Mask" "F.Paste")
		)
		(pad "B-63" smd rect
			(at 4.79869 -16.77035)
			(size 0.24994 1.54991)
			(layers "F.Cu" "F.Mask" "F.Paste")
		)
		(pad "B-64" smd rect
			(at 4.79869 -20.82012)
			(size 0.24994 1.54991)
			(layers "F.Cu" "F.Mask" "F.Paste")
			(net "5721_STATUS")
		)
		(pad "B-65" smd rect
			(at 5.29857 -16.77035)
			(size 0.24994 1.54991)
			(layers "F.Cu" "F.Mask" "F.Paste")
		)
		(pad "B-66" smd rect
			(at 5.29857 -20.82012)
			(size 0.24994 1.54991)
			(layers "F.Cu" "F.Mask" "F.Paste")
		)
		(pad "B-67" smd rect
			(at 5.79869 -16.77035)
			(size 0.24994 1.54991)
			(layers "F.Cu" "F.Mask" "F.Paste")
			(net "SCL")
		)
		(pad "B-68" smd rect
			(at 5.79869 -20.82012)
			(size 0.24994 1.54991)
			(layers "F.Cu" "F.Mask" "F.Paste")
		)
		(pad "B-69" smd rect
			(at 6.29856 -16.77035)
			(size 0.24994 1.54991)
			(layers "F.Cu" "F.Mask" "F.Paste")
			(net "GND")
		)
		(pad "B-70" smd rect
			(at 6.29856 -20.82012)
			(size 0.24994 1.54991)
			(layers "F.Cu" "F.Mask" "F.Paste")
			(net "GND")
		)
		(pad "B-71" smd rect
			(at 6.79869 -16.77035)
			(size 0.24994 1.54991)
			(layers "F.Cu" "F.Mask" "F.Paste")
			(net "UART1_TXD")
		)
		(pad "B-72" smd rect
			(at 6.79869 -20.82012)
			(size 0.24994 1.54991)
			(layers "F.Cu" "F.Mask" "F.Paste")
			(net "MAC_USB+")
		)
		(pad "B-73" smd rect
			(at 7.29856 -16.77035)
			(size 0.24994 1.54991)
			(layers "F.Cu" "F.Mask" "F.Paste")
		)
		(pad "B-74" smd rect
			(at 7.29856 -20.82012)
			(size 0.24994 1.54991)
			(layers "F.Cu" "F.Mask" "F.Paste")
			(net "MAC_USB-")
		)
		(pad "B-75" smd rect
			(at 7.79869 -16.77035)
			(size 0.24994 1.54991)
			(layers "F.Cu" "F.Mask" "F.Paste")
		)
		(pad "B-76" smd rect
			(at 7.79869 -20.82012)
			(size 0.24994 1.54991)
			(layers "F.Cu" "F.Mask" "F.Paste")
		)
		(pad "B-77" smd rect
			(at 8.29856 -16.77035)
			(size 0.24994 1.54991)
			(layers "F.Cu" "F.Mask" "F.Paste")
			(net "UART1_RXD")
		)
		(pad "B-78" smd rect
			(at 8.29856 -20.82012)
			(size 0.24994 1.54991)
			(layers "F.Cu" "F.Mask" "F.Paste")
		)
		(pad "B-79" smd rect
			(at 8.79869 -16.77035)
			(size 0.24994 1.54991)
			(layers "F.Cu" "F.Mask" "F.Paste")
			(net "GPS1_RX")
		)
		(pad "B-80" smd rect
			(at 8.79869 -20.82012)
			(size 0.24994 1.54991)
			(layers "F.Cu" "F.Mask" "F.Paste")
			(net "GPS1_TX")
		)
		(pad "B-81" smd rect
			(at -12.125 -18.8)
			(size 1.35001 1.70002)
			(layers "F.Cu" "F.Mask" "F.Paste")
		)
		(pad "B-82" thru_hole circle
			(at -10.95134 -18.79524)
			(size 0.55016 0.55016)
			(drill 0.55016)
			(layers "*.Cu" "*.Mask")
			(remove_unused_layers no)
			(thermal_bridge_angle 90)
		)
		(pad "B-83" thru_hole circle
			(at 9.04862 -18.79524)
			(size 0.55016 0.55016)
			(drill 0.55016)
			(layers "*.Cu" "*.Mask")
			(remove_unused_layers no)
			(thermal_bridge_angle 90)
		)
		(pad "B-84" smd rect
			(at 10.225 -18.8)
			(size 1.35001 1.70002)
			(layers "F.Cu" "F.Mask" "F.Paste")
		)
		(pad "C-1" smd rect
			(at -21.78647 9.62381)
			(size 1.54991 0.24994)
			(layers "F.Cu" "F.Mask" "F.Paste")
			(net "GPS2_RX")
		)
		(pad "C-2" smd rect
			(at -25.83625 9.62381)
			(size 1.54991 0.24994)
			(layers "F.Cu" "F.Mask" "F.Paste")
			(net "GPS2_TX")
		)
		(pad "C-3" smd rect
			(at -21.78647 9.12368)
			(size 1.54991 0.24994)
			(layers "F.Cu" "F.Mask" "F.Paste")
		)
		(pad "C-4" smd rect
			(at -25.83625 9.12368)
			(size 1.54991 0.24994)
			(layers "F.Cu" "F.Mask" "F.Paste")
		)
		(pad "C-5" smd rect
			(at -21.78647 8.62381)
			(size 1.54991 0.24994)
			(layers "F.Cu" "F.Mask" "F.Paste")
		)
		(pad "C-6" smd rect
			(at -25.83625 8.62381)
			(size 1.54991 0.24994)
			(layers "F.Cu" "F.Mask" "F.Paste")
		)
		(pad "C-7" smd rect
			(at -21.78647 8.12368)
			(size 1.54991 0.24994)
			(layers "F.Cu" "F.Mask" "F.Paste")
		)
		(pad "C-8" smd rect
			(at -25.83625 8.12368)
			(size 1.54991 0.24994)
			(layers "F.Cu" "F.Mask" "F.Paste")
		)
		(pad "C-9" smd rect
			(at -21.78647 7.62381)
			(size 1.54991 0.24994)
			(layers "F.Cu" "F.Mask" "F.Paste")
			(net "GND")
		)
		(pad "C-10" smd rect
			(at -25.83625 7.62381)
			(size 1.54991 0.24994)
			(layers "F.Cu" "F.Mask" "F.Paste")
			(net "GND")
		)
		(pad "C-11" smd rect
			(at -21.78647 7.12369)
			(size 1.54991 0.24994)
			(layers "F.Cu" "F.Mask" "F.Paste")
		)
		(pad "C-12" smd rect
			(at -25.83625 7.12369)
			(size 1.54991 0.24994)
			(layers "F.Cu" "F.Mask" "F.Paste")
		)
		(pad "C-13" smd rect
			(at -21.78647 6.62381)
			(size 1.54991 0.24994)
			(layers "F.Cu" "F.Mask" "F.Paste")
		)
		(pad "C-14" smd rect
			(at -25.83625 6.62381)
			(size 1.54991 0.24994)
			(layers "F.Cu" "F.Mask" "F.Paste")
		)
		(pad "C-15" smd rect
			(at -21.78647 6.12369)
			(size 1.54991 0.24994)
			(layers "F.Cu" "F.Mask" "F.Paste")
		)
		(pad "C-16" smd rect
			(at -25.83625 6.12369)
			(size 1.54991 0.24994)
			(layers "F.Cu" "F.Mask" "F.Paste")
		)
		(pad "C-17" smd rect
			(at -21.78647 5.62382)
			(size 1.54991 0.24994)
			(layers "F.Cu" "F.Mask" "F.Paste")
		)
		(pad "C-18" smd rect
			(at -25.83625 5.62382)
			(size 1.54991 0.24994)
			(layers "F.Cu" "F.Mask" "F.Paste")
		)
		(pad "C-19" smd rect
			(at -21.78647 5.12369)
			(size 1.54991 0.24994)
			(layers "F.Cu" "F.Mask" "F.Paste")
			(net "GND")
		)
		(pad "C-20" smd rect
			(at -25.83625 5.12369)
			(size 1.54991 0.24994)
			(layers "F.Cu" "F.Mask" "F.Paste")
			(net "GND")
		)
		(pad "C-21" smd rect
			(at -21.78647 4.62382)
			(size 1.54991 0.24994)
			(layers "F.Cu" "F.Mask" "F.Paste")
			(net "PCIE_PERST")
		)
		(pad "C-22" smd rect
			(at -25.83625 4.62382)
			(size 1.54991 0.24994)
			(layers "F.Cu" "F.Mask" "F.Paste")
		)
		(pad "C-23" smd rect
			(at -21.78647 4.12369)
			(size 1.54991 0.24994)
			(layers "F.Cu" "F.Mask" "F.Paste")
			(net "KEY1")
		)
		(pad "C-24" smd rect
			(at -25.83625 4.12369)
			(size 1.54991 0.24994)
			(layers "F.Cu" "F.Mask" "F.Paste")
		)
		(pad "C-25" smd rect
			(at -21.78647 3.62382)
			(size 1.54991 0.24994)
			(layers "F.Cu" "F.Mask" "F.Paste")
		)
		(pad "C-26" smd rect
			(at -25.83625 3.62382)
			(size 1.54991 0.24994)
			(layers "F.Cu" "F.Mask" "F.Paste")
		)
		(pad "C-27" smd rect
			(at -21.78647 3.12369)
			(size 1.54991 0.24994)
			(layers "F.Cu" "F.Mask" "F.Paste")
		)
		(pad "C-28" smd rect
			(at -25.83625 3.12369)
			(size 1.54991 0.24994)
			(layers "F.Cu" "F.Mask" "F.Paste")
		)
		(pad "C-29" smd rect
			(at -21.78647 2.62382)
			(size 1.54991 0.24994)
			(layers "F.Cu" "F.Mask" "F.Paste")
			(net "GND")
		)
		(pad "C-30" smd rect
			(at -25.83625 2.62382)
			(size 1.54991 0.24994)
			(layers "F.Cu" "F.Mask" "F.Paste")
			(net "GND")
		)
		(pad "C-31" smd rect
			(at -21.78647 2.1237)
			(size 1.54991 0.24994)
			(layers "F.Cu" "F.Mask" "F.Paste")
			(net "IMU_ENV_SCL")
		)
		(pad "C-32" smd rect
			(at -25.83625 2.1237)
			(size 1.54991 0.24994)
			(layers "F.Cu" "F.Mask" "F.Paste")
		)
		(pad "C-33" smd rect
			(at -21.78647 1.62382)
			(size 1.54991 0.24994)
			(layers "F.Cu" "F.Mask" "F.Paste")
		)
		(pad "C-34" smd rect
			(at -25.83625 1.62382)
			(size 1.54991 0.24994)
			(layers "F.Cu" "F.Mask" "F.Paste")
		)
		(pad "C-35" smd rect
			(at -21.78647 1.1237)
			(size 1.54991 0.24994)
			(layers "F.Cu" "F.Mask" "F.Paste")
		)
		(pad "C-36" smd rect
			(at -25.83625 1.1237)
			(size 1.54991 0.24994)
			(layers "F.Cu" "F.Mask" "F.Paste")
		)
		(pad "C-37" smd rect
			(at -21.78647 0.62383)
			(size 1.54991 0.24994)
			(layers "F.Cu" "F.Mask" "F.Paste")
			(net "IMU_ENV_SDA")
		)
		(pad "C-38" smd rect
			(at -25.83625 0.62383)
			(size 1.54991 0.24994)
			(layers "F.Cu" "F.Mask" "F.Paste")
		)
		(pad "C-39" smd rect
			(at -21.78647 0.1237)
			(size 1.54991 0.24994)
			(layers "F.Cu" "F.Mask" "F.Paste")
			(net "GND")
		)
		(pad "C-40" smd rect
			(at -25.83625 0.1237)
			(size 1.54991 0.24994)
			(layers "F.Cu" "F.Mask" "F.Paste")
			(net "GND")
		)
		(pad "C-41" smd rect
			(at -21.78647 -0.37617)
			(size 1.54991 0.24994)
			(layers "F.Cu" "F.Mask" "F.Paste")
		)
		(pad "C-42" smd rect
			(at -25.83625 -0.37617)
			(size 1.54991 0.24994)
			(layers "F.Cu" "F.Mask" "F.Paste")
		)
		(pad "C-43" smd rect
			(at -21.78647 -0.8763)
			(size 1.54991 0.24994)
			(layers "F.Cu" "F.Mask" "F.Paste")
		)
		(pad "C-44" smd rect
			(at -25.83625 -0.8763)
			(size 1.54991 0.24994)
			(layers "F.Cu" "F.Mask" "F.Paste")
		)
		(pad "C-45" smd rect
			(at -21.78647 -1.37617)
			(size 1.54991 0.24994)
			(layers "F.Cu" "F.Mask" "F.Paste")
		)
		(pad "C-46" smd rect
			(at -25.83625 -1.37617)
			(size 1.54991 0.24994)
			(layers "F.Cu" "F.Mask" "F.Paste")
		)
		(pad "C-47" smd rect
			(at -21.78647 -1.8763)
			(size 1.54991 0.24994)
			(layers "F.Cu" "F.Mask" "F.Paste")
		)
		(pad "C-48" smd rect
			(at -25.83625 -1.8763)
			(size 1.54991 0.24994)
			(layers "F.Cu" "F.Mask" "F.Paste")
		)
		(pad "C-49" smd rect
			(at -21.78647 -2.37617)
			(size 1.54991 0.24994)
			(layers "F.Cu" "F.Mask" "F.Paste")
			(net "GND")
		)
		(pad "C-50" smd rect
			(at -25.83625 -2.37617)
			(size 1.54991 0.24994)
			(layers "F.Cu" "F.Mask" "F.Paste")
			(net "GND")
		)
		(pad "C-51" smd rect
			(at -21.78647 -2.87629)
			(size 1.54991 0.24994)
			(layers "F.Cu" "F.Mask" "F.Paste")
			(net "RTC_MFP")
		)
		(pad "C-52" smd rect
			(at -25.83625 -2.87629)
			(size 1.54991 0.24994)
			(layers "F.Cu" "F.Mask" "F.Paste")
		)
		(pad "C-53" smd rect
			(at -21.78647 -3.37617)
			(size 1.54991 0.24994)
			(layers "F.Cu" "F.Mask" "F.Paste")
		)
		(pad "C-54" smd rect
			(at -25.83625 -3.37617)
			(size 1.54991 0.24994)
			(layers "F.Cu" "F.Mask" "F.Paste")
		)
		(pad "C-55" smd rect
			(at -21.78647 -3.87629)
			(size 1.54991 0.24994)
			(layers "F.Cu" "F.Mask" "F.Paste")
		)
		(pad "C-56" smd rect
			(at -25.83625 -3.87629)
			(size 1.54991 0.24994)
			(layers "F.Cu" "F.Mask" "F.Paste")
		)
		(pad "C-57" smd rect
			(at -21.78647 -4.37616)
			(size 1.54991 0.24994)
			(layers "F.Cu" "F.Mask" "F.Paste")
		)
		(pad "C-58" smd rect
			(at -25.83625 -4.37616)
			(size 1.54991 0.24994)
			(layers "F.Cu" "F.Mask" "F.Paste")
		)
		(pad "C-59" smd rect
			(at -21.78647 -4.87629)
			(size 1.54991 0.24994)
			(layers "F.Cu" "F.Mask" "F.Paste")
			(net "GND")
		)
		(pad "C-60" smd rect
			(at -25.83625 -4.87629)
			(size 1.54991 0.24994)
			(layers "F.Cu" "F.Mask" "F.Paste")
			(net "GND")
		)
		(pad "C-61" smd rect
			(at -21.78647 -5.37616)
			(size 1.54991 0.24994)
			(layers "F.Cu" "F.Mask" "F.Paste")
		)
		(pad "C-62" smd rect
			(at -25.83625 -5.37616)
			(size 1.54991 0.24994)
			(layers "F.Cu" "F.Mask" "F.Paste")
		)
		(pad "C-63" smd rect
			(at -21.78647 -5.87629)
			(size 1.54991 0.24994)
			(layers "F.Cu" "F.Mask" "F.Paste")
		)
		(pad "C-64" smd rect
			(at -25.83625 -5.87629)
			(size 1.54991 0.24994)
			(layers "F.Cu" "F.Mask" "F.Paste")
		)
		(pad "C-65" smd rect
			(at -21.78647 -6.37616)
			(size 1.54991 0.24994)
			(layers "F.Cu" "F.Mask" "F.Paste")
		)
		(pad "C-66" smd rect
			(at -25.83625 -6.37616)
			(size 1.54991 0.24994)
			(layers "F.Cu" "F.Mask" "F.Paste")
		)
		(pad "C-67" smd rect
			(at -21.78647 -6.87629)
			(size 1.54991 0.24994)
			(layers "F.Cu" "F.Mask" "F.Paste")
		)
		(pad "C-68" smd rect
			(at -25.83625 -6.87629)
			(size 1.54991 0.24994)
			(layers "F.Cu" "F.Mask" "F.Paste")
		)
		(pad "C-69" smd rect
			(at -21.78647 -7.37616)
			(size 1.54991 0.24994)
			(layers "F.Cu" "F.Mask" "F.Paste")
			(net "GND")
		)
		(pad "C-70" smd rect
			(at -25.83625 -7.37616)
			(size 1.54991 0.24994)
			(layers "F.Cu" "F.Mask" "F.Paste")
			(net "GND")
		)
		(pad "C-71" smd rect
			(at -21.78647 -7.87628)
			(size 1.54991 0.24994)
			(layers "F.Cu" "F.Mask" "F.Paste")
		)
		(pad "C-72" smd rect
			(at -25.83625 -7.87628)
			(size 1.54991 0.24994)
			(layers "F.Cu" "F.Mask" "F.Paste")
		)
		(pad "C-73" smd rect
			(at -21.78647 -8.37616)
			(size 1.54991 0.24994)
			(layers "F.Cu" "F.Mask" "F.Paste")
		)
		(pad "C-74" smd rect
			(at -25.83625 -8.37616)
			(size 1.54991 0.24994)
			(layers "F.Cu" "F.Mask" "F.Paste")
		)
		(pad "C-75" smd rect
			(at -21.78647 -8.87628)
			(size 1.54991 0.24994)
			(layers "F.Cu" "F.Mask" "F.Paste")
		)
		(pad "C-76" smd rect
			(at -25.83625 -8.87628)
			(size 1.54991 0.24994)
			(layers "F.Cu" "F.Mask" "F.Paste")
		)
		(pad "C-77" smd rect
			(at -21.78647 -9.37615)
			(size 1.54991 0.24994)
			(layers "F.Cu" "F.Mask" "F.Paste")
			(net "FPGA_TCK")
		)
		(pad "C-78" smd rect
			(at -25.83625 -9.37615)
			(size 1.54991 0.24994)
			(layers "F.Cu" "F.Mask" "F.Paste")
			(net "FPGA_TDI")
		)
		(pad "C-79" smd rect
			(at -21.78647 -9.87628)
			(size 1.54991 0.24994)
			(layers "F.Cu" "F.Mask" "F.Paste")
			(net "FPGA_TDO")
		)
		(pad "C-80" smd rect
			(at -25.83625 -9.87628)
			(size 1.54991 0.24994)
			(layers "F.Cu" "F.Mask" "F.Paste")
			(net "FPGA_TMS")
		)
		(pad "C-81" smd rect
			(at -23.8 11.05)
			(size 1.70002 1.35001)
			(layers "F.Cu" "F.Mask" "F.Paste")
		)
		(pad "C-82" thru_hole circle
			(at -23.81136 9.87374)
			(size 0.55016 0.55016)
			(drill 0.55016)
			(layers "*.Cu" "*.Mask")
			(remove_unused_layers no)
			(thermal_bridge_angle 90)
		)
		(pad "C-83" thru_hole circle
			(at -23.81136 -10.12622)
			(size 0.55016 0.55016)
			(drill 0.55016)
			(layers "*.Cu" "*.Mask")
			(remove_unused_layers no)
			(thermal_bridge_angle 90)
		)
		(pad "C-84" smd rect
			(at -23.8 -11.3)
			(size 1.70002 1.35001)
			(layers "F.Cu" "F.Mask" "F.Paste")
		)
		(pad "D-1" smd rect
			(at 8.79894 16.77035)
			(size 0.24994 1.54991)
			(layers "F.Cu" "F.Mask" "F.Paste")
		)
		(pad "D-2" smd rect
			(at 8.79894 20.82013)
			(size 0.24994 1.54991)
			(layers "F.Cu" "F.Mask" "F.Paste")
		)
		(pad "D-3" smd rect
			(at 8.29881 16.77035)
			(size 0.24994 1.54991)
			(layers "F.Cu" "F.Mask" "F.Paste")
		)
		(pad "D-4" smd rect
			(at 8.29881 20.82013)
			(size 0.24994 1.54991)
			(layers "F.Cu" "F.Mask" "F.Paste")
		)
		(pad "D-5" smd rect
			(at 7.79894 16.77035)
			(size 0.24994 1.54991)
			(layers "F.Cu" "F.Mask" "F.Paste")
		)
		(pad "D-6" smd rect
			(at 7.79894 20.82013)
			(size 0.24994 1.54991)
			(layers "F.Cu" "F.Mask" "F.Paste")
		)
		(pad "D-7" smd rect
			(at 7.29882 16.77035)
			(size 0.24994 1.54991)
			(layers "F.Cu" "F.Mask" "F.Paste")
		)
		(pad "D-8" smd rect
			(at 7.29882 20.82013)
			(size 0.24994 1.54991)
			(layers "F.Cu" "F.Mask" "F.Paste")
		)
		(pad "D-9" smd rect
			(at 6.79894 16.77035)
			(size 0.24994 1.54991)
			(layers "F.Cu" "F.Mask" "F.Paste")
			(net "GND")
		)
		(pad "D-10" smd rect
			(at 6.79894 20.82013)
			(size 0.24994 1.54991)
			(layers "F.Cu" "F.Mask" "F.Paste")
			(net "GND")
		)
		(pad "D-11" smd rect
			(at 6.29882 16.77035)
			(size 0.24994 1.54991)
			(layers "F.Cu" "F.Mask" "F.Paste")
		)
	)
)
